FILE_TYPE = MULTI_PHYS_TABLE;
PART 'CONN4_H73295001'
{======================================================================================================================================================================================}
:PACK_TYPE  |MATERIAL  |PART_NUMBER     = EnvComp |PART_NUMBER   |JEDEC_TYPE              |CLASS  |DESCRIPTION                          |HEIGHT      |COMPONENT_TYPE  |LEAD_LENGTH  | SPEED_URL | Status |RPL| AML | Bus_Unit | Days;
{======================================================================================================================================================================================}
'PIP'       | 'CONN'   | 'H73295-001'(!) = ''     | 'H73295-001' | 'CONN4_H73295001_PIP' | 'IO'  | 'CONN_HDR,1X4,RCP,VT,2.5mm,9ST,BK'   | '0.415 IN' | 'THMT'         | '0.142'     | 'http://speed.intel.com:8081/speed/module/pdm/item/pdm_item_detail_direct.asp?item_cde=H73295-001&item_rev=01&url_param=unused' | '' | '' | '' | '' | '' 
'PIP'       | 'EMPTY'  | 'H73295-001'(!) = ''     | 'H73295-001' | 'CONN4_H73295001_PIP' | 'IO'  | 'CONN_HDR,1X4,RCP,VT,2.5mm,9ST,BK'   | '0.415 IN' | 'THMT'         | '0.142'     | 'http://speed.intel.com:8081/speed/module/pdm/item/pdm_item_detail_direct.asp?item_cde=H73295-001&item_rev=01&url_param=unused' | '' | '' | '' | '' | '' 
END_PART
END.
